(kicad_pcb
	(version 20260206)
	(generator "pcbnew")
	(generator_version "10.0")
	(general
		(thickness 1.6)
		(legacy_teardrops no)
	)
	(paper "A4")
	(title_block
		(title "Wiwynn_Tioga_Pass_MB.brd")
		(comment 1 "Tioga Pass / footprints 3365-3371 of 4770")
	)
	(layers
		(0 "F.Cu" signal "TOP")
		(4 "In1.Cu" signal "L2GND")
		(6 "In2.Cu" signal "L3")
		(8 "In3.Cu" signal "L4GND")
		(10 "In4.Cu" signal "L5")
		(12 "In5.Cu" signal "L6GND")
		(14 "In6.Cu" signal "L7VCC")
		(16 "In7.Cu" signal "L8VCC")
		(18 "In8.Cu" signal "L9GND")
		(20 "In9.Cu" signal "L10")
		(22 "In10.Cu" signal "L11GND")
		(24 "In11.Cu" signal "L12")
		(26 "In12.Cu" signal "L13GND")
		(2 "B.Cu" signal "BOTTOM")
		(9 "F.Adhes" user "F.Adhesive")
		(11 "B.Adhes" user "B.Adhesive")
		(13 "F.Paste" user "Package Geometry/Pastemask Top")
		(15 "B.Paste" user "Package Geometry/Pastemask Bottom")
		(5 "F.SilkS" user "Ref Des/Silkscreen Top")
		(7 "B.SilkS" user "Ref Des/Silkscreen Bottom")
		(1 "F.Mask" user "Board Geometry/Soldermask Top")
		(3 "B.Mask" user "Board Geometry/Soldermask Bottom")
		(17 "Dwgs.User" user "User.Drawings")
		(19 "Cmts.User" user "User.Comments")
		(21 "Eco1.User" user "User.Eco1")
		(23 "Eco2.User" user "User.Eco2")
		(25 "Edge.Cuts" user "Board Geometry/Outline")
		(27 "Margin" user)
		(31 "F.CrtYd" user "Package Geometry/Place Bound Top")
		(29 "B.CrtYd" user "Package Geometry/Place Bound Bottom")
		(35 "F.Fab" user "Ref Des/Assembly Top")
		(33 "B.Fab" user "Ref Des/Assembly Bottom")
	)
	(footprint ""
		(layer "B.Cu")
		(at 333.659226 -39.539418 90)
		(property "Reference" "C3T1"
			(at 0 0 90)
			(layer "B.SilkS")
			(hide yes)
			(effects
				(font
					(size 1.27 1.27)
				)
				(justify mirror)
			)
		)
		(property "Value" ""
			(at 0 0 90)
			(layer "B.Fab")
			(effects
				(font
					(size 1.27 1.27)
				)
				(justify mirror)
			)
		)
		(duplicate_pad_numbers_are_jumpers no)
		(fp_rect
			(start 0.500126 1.598422)
			(end -0.500126 -0.201422)
			(stroke
				(width 0)
				(type default)
			)
			(fill no)
			(layer "B.CrtYd")
		)
		(fp_line
			(start 0.500126 -0.201422)
			(end -0.500126 -0.201422)
			(stroke
				(width 0.1)
				(type default)
			)
			(layer "B.Fab")
		)
		(fp_line
			(start -0.500126 -0.201422)
			(end -0.500126 1.598422)
			(stroke
				(width 0.1)
				(type default)
			)
			(layer "B.Fab")
		)
		(fp_line
			(start 0.500126 1.598422)
			(end 0.500126 -0.201422)
			(stroke
				(width 0.1)
				(type default)
			)
			(layer "B.Fab")
		)
		(fp_line
			(start -0.500126 1.598422)
			(end 0.500126 1.598422)
			(stroke
				(width 0.1)
				(type default)
			)
			(layer "B.Fab")
		)
		(pad "1" smd rect
			(at 0 0)
			(size 0.889 0.9906)
			(layers "B.Cu" "B.Mask" "B.Paste")
			(net "P1V8_MCP_CPU0")
		)
		(pad "2" smd rect
			(at 0 1.397)
			(size 0.889 0.9906)
			(layers "B.Cu" "B.Mask" "B.Paste")
			(net "GND")
		)
		(zone
			(layer "B.Cu")
			(hatch none 0.5)
			(connect_pads
				(clearance 0)
			)
			(min_thickness 0.25)
			(keepout
				(tracks not_allowed)
				(vias allowed)
				(pads allowed)
				(copperpour not_allowed)
				(footprints allowed)
			)
			(placement
				(enabled no)
				(sheetname "")
			)
			(fill
				(thermal_gap 0.5)
				(thermal_bridge_width 0.5)
				(island_removal_mode 0)
			)
			(polygon
				(pts
					(xy 334.611726 -40.034718) (xy 334.103726 -40.034718) (xy 334.103726 -39.044118) (xy 334.611726 -39.044118)
				)
			)
		)
		(zone
			(layer "B.Cu")
			(hatch none 0.5)
			(connect_pads
				(clearance 0)
			)
			(min_thickness 0.25)
			(keepout
				(tracks allowed)
				(vias not_allowed)
				(pads allowed)
				(copperpour not_allowed)
				(footprints allowed)
			)
			(placement
				(enabled no)
				(sheetname "")
			)
			(fill
				(thermal_gap 0.5)
				(thermal_bridge_width 0.5)
				(island_removal_mode 0)
			)
			(polygon
				(pts
					(xy 334.611726 -40.034718) (xy 334.103726 -40.034718) (xy 334.103726 -39.044118) (xy 334.611726 -39.044118)
				)
			)
		)
	)
	(footprint ""
		(layer "B.Cu")
		(at 166.66718 -145.97126 180)
		(property "Reference" "C6W13"
			(at -1.47828 0.78994 270)
			(unlocked yes)
			(layer "B.SilkS")
			(effects
				(font
					(size 0.4064 0.254)
					(thickness 0.1524)
				)
				(justify mirror)
			)
		)
		(property "Value" ""
			(at 0 0 0)
			(layer "B.Fab")
			(effects
				(font
					(size 1.27 1.27)
				)
				(justify mirror)
			)
		)
		(duplicate_pad_numbers_are_jumpers no)
		(fp_poly
			(pts
				(xy 0.7239 -0.2159) (xy -0.7239 -0.2159) (xy -0.7239 1.9939) (xy 0.7239 1.9939)
			)
			(stroke
				(width 0)
				(type default)
			)
			(fill no)
			(layer "B.CrtYd")
		)
		(fp_line
			(start 0.7239 1.9939)
			(end -0.7239 1.9939)
			(stroke
				(width 0.1)
				(type default)
			)
			(layer "B.Fab")
		)
		(fp_line
			(start 0.7239 -0.2159)
			(end 0.7239 1.9939)
			(stroke
				(width 0.1)
				(type default)
			)
			(layer "B.Fab")
		)
		(fp_line
			(start -0.7239 1.9939)
			(end -0.7239 -0.2159)
			(stroke
				(width 0.1)
				(type default)
			)
			(layer "B.Fab")
		)
		(fp_line
			(start -0.7239 -0.2159)
			(end 0.7239 -0.2159)
			(stroke
				(width 0.1)
				(type default)
			)
			(layer "B.Fab")
		)
		(pad "1" smd rect
			(at 0 0)
			(size 1.27 1.016)
			(layers "B.Cu" "B.Mask" "B.Paste")
			(net "PVTT_KLM")
		)
		(pad "2" smd rect
			(at 0 1.778)
			(size 1.27 1.016)
			(layers "B.Cu" "B.Mask" "B.Paste")
			(net "GND")
		)
		(zone
			(layer "B.Cu")
			(hatch none 0.5)
			(connect_pads
				(clearance 0)
			)
			(min_thickness 0.25)
			(keepout
				(tracks not_allowed)
				(vias allowed)
				(pads allowed)
				(copperpour not_allowed)
				(footprints allowed)
			)
			(placement
				(enabled no)
				(sheetname "")
			)
			(fill
				(thermal_gap 0.5)
				(thermal_bridge_width 0.5)
				(island_removal_mode 0)
			)
			(polygon
				(pts
					(xy 166.03218 -146.47926) (xy 167.30218 -146.47926) (xy 167.30218 -147.24126) (xy 166.03218 -147.24126)
				)
			)
		)
	)
	(footprint ""
		(layer "B.Cu")
		(at 396.113 -87.3125 180)
		(property "Reference" "R2N32"
			(at 0.8382 -0.67818 180)
			(unlocked yes)
			(layer "B.SilkS")
			(effects
				(font
					(size 0.4064 0.254)
					(thickness 0.1524)
				)
				(justify left mirror)
			)
		)
		(property "Value" ""
			(at 0 0 0)
			(layer "B.Fab")
			(effects
				(font
					(size 1.27 1.27)
				)
				(justify mirror)
			)
		)
		(duplicate_pad_numbers_are_jumpers no)
		(fp_poly
			(pts
				(xy 0.2794 -0.1016) (xy -0.2794 -0.1016) (xy -0.2794 0.9906) (xy 0.2794 0.9906)
			)
			(stroke
				(width 0)
				(type default)
			)
			(fill no)
			(layer "B.CrtYd")
		)
		(fp_line
			(start 0.2794 0.9906)
			(end -0.2794 0.9906)
			(stroke
				(width 0.1)
				(type default)
			)
			(layer "B.Fab")
		)
		(fp_line
			(start 0.2794 -0.1016)
			(end 0.2794 0.9906)
			(stroke
				(width 0.1)
				(type default)
			)
			(layer "B.Fab")
		)
		(fp_line
			(start -0.2794 0.9906)
			(end -0.2794 -0.1016)
			(stroke
				(width 0.1)
				(type default)
			)
			(layer "B.Fab")
		)
		(fp_line
			(start -0.2794 -0.1016)
			(end 0.2794 -0.1016)
			(stroke
				(width 0.1)
				(type default)
			)
			(layer "B.Fab")
		)
		(pad "1" smd rect
			(at 0 0)
			(size 0.508 0.508)
			(layers "B.Cu" "B.Mask" "B.Paste")
			(net "P3V3_STBY")
		)
		(pad "2" smd rect
			(at 0 0.889)
			(size 0.508 0.508)
			(layers "B.Cu" "B.Mask" "B.Paste")
			(net "FM_BIOS_SMI_ACTIVE_N")
		)
		(zone
			(layer "B.Cu")
			(hatch none 0.5)
			(connect_pads
				(clearance 0)
			)
			(min_thickness 0.25)
			(keepout
				(tracks not_allowed)
				(vias allowed)
				(pads allowed)
				(copperpour not_allowed)
				(footprints allowed)
			)
			(placement
				(enabled no)
				(sheetname "")
			)
			(fill
				(thermal_gap 0.5)
				(thermal_bridge_width 0.5)
				(island_removal_mode 0)
			)
			(polygon
				(pts
					(xy 395.859 -87.9475) (xy 396.367 -87.9475) (xy 396.367 -87.5665) (xy 395.859 -87.5665)
				)
			)
		)
		(zone
			(layer "B.Cu")
			(hatch none 0.5)
			(connect_pads
				(clearance 0)
			)
			(min_thickness 0.25)
			(keepout
				(tracks allowed)
				(vias not_allowed)
				(pads allowed)
				(copperpour not_allowed)
				(footprints allowed)
			)
			(placement
				(enabled no)
				(sheetname "")
			)
			(fill
				(thermal_gap 0.5)
				(thermal_bridge_width 0.5)
				(island_removal_mode 0)
			)
			(polygon
				(pts
					(xy 395.859 -87.5665) (xy 396.367 -87.5665) (xy 396.367 -87.9475) (xy 395.859 -87.9475)
				)
			)
		)
	)
	(footprint ""
		(layer "B.Cu")
		(at 104.5591 -145.0086 90)
		(property "Reference" "C8L5"
			(at -1.848866 0.752348 90)
			(unlocked yes)
			(layer "B.SilkS")
			(effects
				(font
					(size 1.27 0.9652)
					(thickness 0.1524)
				)
				(justify mirror)
			)
		)
		(property "Value" ""
			(at 0 0 90)
			(layer "B.Fab")
			(effects
				(font
					(size 1.27 1.27)
				)
				(justify mirror)
			)
		)
		(duplicate_pad_numbers_are_jumpers no)
		(fp_rect
			(start 0.500126 1.598422)
			(end -0.500126 -0.201422)
			(stroke
				(width 0)
				(type default)
			)
			(fill no)
			(layer "B.CrtYd")
		)
		(fp_line
			(start 0.500126 -0.201422)
			(end -0.500126 -0.201422)
			(stroke
				(width 0.1)
				(type default)
			)
			(layer "B.Fab")
		)
		(fp_line
			(start -0.500126 -0.201422)
			(end -0.500126 1.598422)
			(stroke
				(width 0.1)
				(type default)
			)
			(layer "B.Fab")
		)
		(fp_line
			(start 0.500126 1.598422)
			(end 0.500126 -0.201422)
			(stroke
				(width 0.1)
				(type default)
			)
			(layer "B.Fab")
		)
		(fp_line
			(start -0.500126 1.598422)
			(end 0.500126 1.598422)
			(stroke
				(width 0.1)
				(type default)
			)
			(layer "B.Fab")
		)
		(pad "1" smd rect
			(at 0 0)
			(size 0.889 0.9906)
			(layers "B.Cu" "B.Mask" "B.Paste")
			(net "PVDDQ_KLM")
		)
		(pad "2" smd rect
			(at 0 1.397)
			(size 0.889 0.9906)
			(layers "B.Cu" "B.Mask" "B.Paste")
			(net "GND")
		)
		(zone
			(layer "B.Cu")
			(hatch none 0.5)
			(connect_pads
				(clearance 0)
			)
			(min_thickness 0.25)
			(keepout
				(tracks allowed)
				(vias not_allowed)
				(pads allowed)
				(copperpour not_allowed)
				(footprints allowed)
			)
			(placement
				(enabled no)
				(sheetname "")
			)
			(fill
				(thermal_gap 0.5)
				(thermal_bridge_width 0.5)
				(island_removal_mode 0)
			)
			(polygon
				(pts
					(xy 105.5116 -145.5039) (xy 105.0036 -145.5039) (xy 105.0036 -144.5133) (xy 105.5116 -144.5133)
				)
			)
		)
		(zone
			(layer "B.Cu")
			(hatch none 0.5)
			(connect_pads
				(clearance 0)
			)
			(min_thickness 0.25)
			(keepout
				(tracks not_allowed)
				(vias allowed)
				(pads allowed)
				(copperpour not_allowed)
				(footprints allowed)
			)
			(placement
				(enabled no)
				(sheetname "")
			)
			(fill
				(thermal_gap 0.5)
				(thermal_bridge_width 0.5)
				(island_removal_mode 0)
			)
			(polygon
				(pts
					(xy 105.5116 -145.5039) (xy 105.0036 -145.5039) (xy 105.0036 -144.5133) (xy 105.5116 -144.5133)
				)
			)
		)
	)
	(footprint ""
		(layer "B.Cu")
		(at 1.9304 -8.4582)
		(property "Reference" "CT28"
			(at 0.8382 -0.84963 0)
			(unlocked yes)
			(layer "B.SilkS")
			(effects
				(font
					(size 0.7874 0.5842)
					(thickness 0.1524)
				)
				(justify left mirror)
			)
		)
		(property "Value" ""
			(at 0 0 0)
			(layer "B.Fab")
			(effects
				(font
					(size 1.27 1.27)
				)
				(justify mirror)
			)
		)
		(duplicate_pad_numbers_are_jumpers no)
		(fp_poly
			(pts
				(xy -0.3048 -0.1016) (xy -0.3048 0.9906) (xy 0.3048 0.9906) (xy 0.3048 -0.1016)
			)
			(stroke
				(width 0)
				(type default)
			)
			(fill no)
			(layer "B.CrtYd")
		)
		(fp_line
			(start -0.3048 -0.1016)
			(end 0.3048 -0.1016)
			(stroke
				(width 0.1)
				(type default)
			)
			(layer "B.Fab")
		)
		(fp_line
			(start -0.3048 0.9906)
			(end -0.3048 -0.1016)
			(stroke
				(width 0.1)
				(type default)
			)
			(layer "B.Fab")
		)
		(fp_line
			(start 0.3048 -0.1016)
			(end 0.3048 0.9906)
			(stroke
				(width 0.1)
				(type default)
			)
			(layer "B.Fab")
		)
		(fp_line
			(start 0.3048 0.9906)
			(end -0.3048 0.9906)
			(stroke
				(width 0.1)
				(type default)
			)
			(layer "B.Fab")
		)
		(pad "1" smd rect
			(at 0 0 180)
			(size 0.508 0.508)
			(layers "B.Cu" "B.Mask" "B.Paste")
			(net "A_TSENSE_PVDDQ_GHJ")
		)
		(pad "2" smd rect
			(at 0 0.889 180)
			(size 0.508 0.508)
			(layers "B.Cu" "B.Mask" "B.Paste")
			(net "GND")
		)
		(zone
			(layer "B.Cu")
			(hatch none 0.5)
			(connect_pads
				(clearance 0)
			)
			(min_thickness 0.25)
			(keepout
				(tracks allowed)
				(vias not_allowed)
				(pads allowed)
				(copperpour not_allowed)
				(footprints allowed)
			)
			(placement
				(enabled no)
				(sheetname "")
			)
			(fill
				(thermal_gap 0.5)
				(thermal_bridge_width 0.5)
				(island_removal_mode 0)
			)
			(polygon
				(pts
					(xy 2.1844 -8.2042) (xy 1.6764 -8.2042) (xy 1.6764 -7.8232) (xy 2.1844 -7.8232)
				)
			)
		)
		(zone
			(layer "B.Cu")
			(hatch none 0.5)
			(connect_pads
				(clearance 0)
			)
			(min_thickness 0.25)
			(keepout
				(tracks not_allowed)
				(vias allowed)
				(pads allowed)
				(copperpour not_allowed)
				(footprints allowed)
			)
			(placement
				(enabled no)
				(sheetname "")
			)
			(fill
				(thermal_gap 0.5)
				(thermal_bridge_width 0.5)
				(island_removal_mode 0)
			)
			(polygon
				(pts
					(xy 2.1844 -7.8232) (xy 1.6764 -7.8232) (xy 1.6764 -8.2042) (xy 2.1844 -8.2042)
				)
			)
		)
	)
	(footprint ""
		(layer "B.Cu")
		(at 402.463 -148.1074 180)
		(property "Reference" "R2L19"
			(at 0 0 0)
			(layer "B.SilkS")
			(hide yes)
			(effects
				(font
					(size 1.27 1.27)
				)
				(justify mirror)
			)
		)
		(property "Value" ""
			(at 0 0 0)
			(layer "B.Fab")
			(effects
				(font
					(size 1.27 1.27)
				)
				(justify mirror)
			)
		)
		(duplicate_pad_numbers_are_jumpers no)
		(fp_poly
			(pts
				(xy 0.2794 -0.1016) (xy -0.2794 -0.1016) (xy -0.2794 0.9906) (xy 0.2794 0.9906)
			)
			(stroke
				(width 0)
				(type default)
			)
			(fill no)
			(layer "B.CrtYd")
		)
		(fp_line
			(start 0.2794 0.9906)
			(end -0.2794 0.9906)
			(stroke
				(width 0.1)
				(type default)
			)
			(layer "B.Fab")
		)
		(fp_line
			(start 0.2794 -0.1016)
			(end 0.2794 0.9906)
			(stroke
				(width 0.1)
				(type default)
			)
			(layer "B.Fab")
		)
		(fp_line
			(start -0.2794 0.9906)
			(end -0.2794 -0.1016)
			(stroke
				(width 0.1)
				(type default)
			)
			(layer "B.Fab")
		)
		(fp_line
			(start -0.2794 -0.1016)
			(end 0.2794 -0.1016)
			(stroke
				(width 0.1)
				(type default)
			)
			(layer "B.Fab")
		)
		(pad "1" smd rect
			(at 0 0)
			(size 0.508 0.508)
			(layers "B.Cu" "B.Mask" "B.Paste")
			(net "VR_P1V8_PCH_STBY_FB")
		)
		(pad "2" smd rect
			(at 0 0.889)
			(size 0.508 0.508)
			(layers "B.Cu" "B.Mask" "B.Paste")
			(net "GND")
		)
		(zone
			(layer "B.Cu")
			(hatch none 0.5)
			(connect_pads
				(clearance 0)
			)
			(min_thickness 0.25)
			(keepout
				(tracks not_allowed)
				(vias allowed)
				(pads allowed)
				(copperpour not_allowed)
				(footprints allowed)
			)
			(placement
				(enabled no)
				(sheetname "")
			)
			(fill
				(thermal_gap 0.5)
				(thermal_bridge_width 0.5)
				(island_removal_mode 0)
			)
			(polygon
				(pts
					(xy 402.209 -148.7424) (xy 402.717 -148.7424) (xy 402.717 -148.3614) (xy 402.209 -148.3614)
				)
			)
		)
		(zone
			(layer "B.Cu")
			(hatch none 0.5)
			(connect_pads
				(clearance 0)
			)
			(min_thickness 0.25)
			(keepout
				(tracks allowed)
				(vias not_allowed)
				(pads allowed)
				(copperpour not_allowed)
				(footprints allowed)
			)
			(placement
				(enabled no)
				(sheetname "")
			)
			(fill
				(thermal_gap 0.5)
				(thermal_bridge_width 0.5)
				(island_removal_mode 0)
			)
			(polygon
				(pts
					(xy 402.209 -148.3614) (xy 402.717 -148.3614) (xy 402.717 -148.7424) (xy 402.209 -148.7424)
				)
			)
		)
	)
	(footprint ""
		(layer "B.Cu")
		(at 374.777 -90.2335 180)
		(property "Reference" "R7C10"
			(at 0 0 0)
			(layer "B.SilkS")
			(hide yes)
			(effects
				(font
					(size 1.27 1.27)
				)
				(justify mirror)
			)
		)
		(property "Value" ""
			(at 0 0 0)
			(layer "B.Fab")
			(effects
				(font
					(size 1.27 1.27)
				)
				(justify mirror)
			)
		)
		(duplicate_pad_numbers_are_jumpers no)
		(fp_poly
			(pts
				(xy 0.2794 -0.1016) (xy -0.2794 -0.1016) (xy -0.2794 0.9906) (xy 0.2794 0.9906)
			)
			(stroke
				(width 0)
				(type default)
			)
			(fill no)
			(layer "B.CrtYd")
		)
		(fp_line
			(start 0.2794 0.9906)
			(end -0.2794 0.9906)
			(stroke
				(width 0.1)
				(type default)
			)
			(layer "B.Fab")
		)
		(fp_line
			(start 0.2794 -0.1016)
			(end 0.2794 0.9906)
			(stroke
				(width 0.1)
				(type default)
			)
			(layer "B.Fab")
		)
		(fp_line
			(start -0.2794 0.9906)
			(end -0.2794 -0.1016)
			(stroke
				(width 0.1)
				(type default)
			)
			(layer "B.Fab")
		)
		(fp_line
			(start -0.2794 -0.1016)
			(end 0.2794 -0.1016)
			(stroke
				(width 0.1)
				(type default)
			)
			(layer "B.Fab")
		)
		(pad "1" smd rect
			(at 0 0)
			(size 0.508 0.508)
			(layers "B.Cu" "B.Mask" "B.Paste")
			(net "P3V3_RTC_STBY")
		)
		(pad "2" smd rect
			(at 0 0.889)
			(size 0.508 0.508)
			(layers "B.Cu" "B.Mask" "B.Paste")
			(net "RST_RTCRST_N")
		)
		(zone
			(layer "B.Cu")
			(hatch none 0.5)
			(connect_pads
				(clearance 0)
			)
			(min_thickness 0.25)
			(keepout
				(tracks not_allowed)
				(vias allowed)
				(pads allowed)
				(copperpour not_allowed)
				(footprints allowed)
			)
			(placement
				(enabled no)
				(sheetname "")
			)
			(fill
				(thermal_gap 0.5)
				(thermal_bridge_width 0.5)
				(island_removal_mode 0)
			)
			(polygon
				(pts
					(xy 374.523 -90.8685) (xy 375.031 -90.8685) (xy 375.031 -90.4875) (xy 374.523 -90.4875)
				)
			)
		)
		(zone
			(layer "B.Cu")
			(hatch none 0.5)
			(connect_pads
				(clearance 0)
			)
			(min_thickness 0.25)
			(keepout
				(tracks allowed)
				(vias not_allowed)
				(pads allowed)
				(copperpour not_allowed)
				(footprints allowed)
			)
			(placement
				(enabled no)
				(sheetname "")
			)
			(fill
				(thermal_gap 0.5)
				(thermal_bridge_width 0.5)
				(island_removal_mode 0)
			)
			(polygon
				(pts
					(xy 374.523 -90.4875) (xy 375.031 -90.4875) (xy 375.031 -90.8685) (xy 374.523 -90.8685)
				)
			)
		)
	)
)
